(kicad_pcb
	(version 20260206)
	(generator "pcbnew")
	(generator_version "10.0")
	(general
		(thickness 1.6)
		(legacy_teardrops no)
	)
	(paper "A4")
	(title_block
		(title "peb — Lightning_PEB_BRD.brd")
		(comment 1 "Lightning (Wiwynn / Facebook NVMe JBOF) / footprints 301-305 of 2563")
	)
	(layers
		(0 "F.Cu" signal "TOP")
		(4 "In1.Cu" signal "L2GND")
		(6 "In2.Cu" signal "L3")
		(8 "In3.Cu" signal "L4VCC")
		(10 "In4.Cu" signal "L5VCC")
		(12 "In5.Cu" signal "L6")
		(14 "In6.Cu" signal "L7GND")
		(2 "B.Cu" signal "BOTTOM")
		(9 "F.Adhes" user "F.Adhesive")
		(11 "B.Adhes" user "B.Adhesive")
		(13 "F.Paste" user "Package Geometry/Pastemask Top")
		(15 "B.Paste" user "Package Geometry/Pastemask Bottom")
		(5 "F.SilkS" user "Ref Des/Silkscreen Top")
		(7 "B.SilkS" user "Ref Des/Silkscreen Bottom")
		(1 "F.Mask" user "Board Geometry/Soldermask Top")
		(3 "B.Mask" user "Board Geometry/Soldermask Bottom")
		(17 "Dwgs.User" user "User.Drawings")
		(19 "Cmts.User" user "User.Comments")
		(21 "Eco1.User" user "User.Eco1")
		(23 "Eco2.User" user "User.Eco2")
		(25 "Edge.Cuts" user "Board Geometry/Outline")
		(27 "Margin" user)
		(31 "F.CrtYd" user "Package Geometry/Place Bound Top")
		(29 "B.CrtYd" user "Package Geometry/Place Bound Bottom")
		(35 "F.Fab" user "Ref Des/Assembly Top")
		(33 "B.Fab" user "Ref Des/Assembly Bottom")
	)
	(footprint ""
		(layer "F.Cu")
		(at 213.424008 -10.287 180)
		(property "Reference" "U6"
			(at 0 0 180)
			(layer "F.SilkS")
			(hide yes)
			(effects
				(font
					(size 1.27 1.27)
				)
			)
		)
		(property "Value" "SNLVC8T245DGVR-GP"
			(at 0 -11.1252 180)
			(unlocked yes)
			(layer "F.Fab")
			(hide yes)
			(effects
				(font
					(size 1.016 1.016)
					(thickness 0.1524)
				)
			)
		)
		(property "Device Type" "TVSOP24H48"
			(at 0 -12.6492 180)
			(unlocked yes)
			(layer "F.Fab")
			(hide yes)
			(effects
				(font
					(size 1.016 1.016)
					(thickness 0.1524)
				)
			)
		)
		(duplicate_pad_numbers_are_jumpers no)
		(fp_line
			(start 2.2987 1.397)
			(end 2.2987 -1.397)
			(stroke
				(width 0.1524)
				(type default)
			)
			(layer "F.SilkS")
		)
		(fp_line
			(start 2.2987 -1.397)
			(end -2.9337 -1.397)
			(stroke
				(width 0.1524)
				(type default)
			)
			(layer "F.SilkS")
		)
		(fp_line
			(start -2.5654 0)
			(end -2.9337 0.3683)
			(stroke
				(width 0.1524)
				(type default)
			)
			(layer "F.SilkS")
		)
		(fp_line
			(start -2.7559 1.397)
			(end -2.7559 3.8354)
			(stroke
				(width 0.508)
				(type default)
			)
			(layer "F.SilkS")
		)
		(fp_line
			(start -2.9337 1.397)
			(end 2.2987 1.397)
			(stroke
				(width 0.1524)
				(type default)
			)
			(layer "F.SilkS")
		)
		(fp_line
			(start -2.9337 -0.3683)
			(end -2.5654 0)
			(stroke
				(width 0.1524)
				(type default)
			)
			(layer "F.SilkS")
		)
		(fp_line
			(start -2.9337 -1.397)
			(end -2.9337 1.397)
			(stroke
				(width 0.1524)
				(type default)
			)
			(layer "F.SilkS")
		)
		(fp_rect
			(start -3.0099 4.0894)
			(end 3.0099 -4.0894)
			(stroke
				(width 0)
				(type default)
			)
			(fill no)
			(layer "F.CrtYd")
		)
		(fp_poly
			(pts
				(xy -3.0099 -4.0894) (xy 3.0099 -4.0894) (xy 3.0099 4.0894) (xy -3.0099 4.0894)
			)
			(stroke
				(width 0)
				(type default)
			)
			(fill no)
			(layer "F.Fab")
		)
		(pad "1" smd rect
			(at -2.19964 2.8194 180)
			(size 0.2032 1.524)
			(layers "F.Cu" "F.Mask" "F.Paste")
			(net "DUT_VDDO")
		)
		(pad "2" smd rect
			(at -1.79959 2.8194 180)
			(size 0.2032 1.524)
			(layers "F.Cu" "F.Mask" "F.Paste")
			(net "GND")
		)
		(pad "3" smd rect
			(at -1.39954 2.8194 180)
			(size 0.2032 1.524)
			(layers "F.Cu" "F.Mask" "F.Paste")
			(net "HOST1_RST_N_LS")
		)
		(pad "4" smd rect
			(at -0.99949 2.8194 180)
			(size 0.2032 1.524)
			(layers "F.Cu" "F.Mask" "F.Paste")
			(net "HOST2_RST_N_LS")
		)
		(pad "5" smd rect
			(at -0.59944 2.8194 180)
			(size 0.2032 1.524)
			(layers "F.Cu" "F.Mask" "F.Paste")
			(net "HOST3_RST_N_LS")
		)
		(pad "6" smd rect
			(at -0.19939 2.8194 180)
			(size 0.2032 1.524)
			(layers "F.Cu" "F.Mask" "F.Paste")
			(net "HOST4_RST_N_LS")
		)
		(pad "7" smd rect
			(at 0.19939 2.8194 180)
			(size 0.2032 1.524)
			(layers "F.Cu" "F.Mask" "F.Paste")
			(net "HOST5_RST_N_LS")
		)
		(pad "8" smd rect
			(at 0.59944 2.8194 180)
			(size 0.2032 1.524)
			(layers "F.Cu" "F.Mask" "F.Paste")
			(net "HOST6_RST_N_LS")
		)
		(pad "9" smd rect
			(at 0.99949 2.8194 180)
			(size 0.2032 1.524)
			(layers "F.Cu" "F.Mask" "F.Paste")
			(net "HOST7_RST_N_LS")
		)
		(pad "10" smd rect
			(at 1.39954 2.8194 180)
			(size 0.2032 1.524)
			(layers "F.Cu" "F.Mask" "F.Paste")
			(net "HOST8_RST_N_LS")
		)
		(pad "11" smd rect
			(at 1.79959 2.8194 180)
			(size 0.2032 1.524)
			(layers "F.Cu" "F.Mask" "F.Paste")
			(net "GND")
		)
		(pad "12" smd rect
			(at 2.19964 2.8194 180)
			(size 0.2032 1.524)
			(layers "F.Cu" "F.Mask" "F.Paste")
			(net "GND")
		)
		(pad "13" smd rect
			(at 2.19964 -2.8194 180)
			(size 0.2032 1.524)
			(layers "F.Cu" "F.Mask" "F.Paste")
			(net "GND")
		)
		(pad "14" smd rect
			(at 1.79959 -2.8194 180)
			(size 0.2032 1.524)
			(layers "F.Cu" "F.Mask" "F.Paste")
			(net "HOST8_RST_N")
		)
		(pad "15" smd rect
			(at 1.39954 -2.8194 180)
			(size 0.2032 1.524)
			(layers "F.Cu" "F.Mask" "F.Paste")
			(net "HOST7_RST_N")
		)
		(pad "16" smd rect
			(at 0.99949 -2.8194 180)
			(size 0.2032 1.524)
			(layers "F.Cu" "F.Mask" "F.Paste")
			(net "HOST6_RST_N")
		)
		(pad "17" smd rect
			(at 0.59944 -2.8194 180)
			(size 0.2032 1.524)
			(layers "F.Cu" "F.Mask" "F.Paste")
			(net "HOST5_RST_N")
		)
		(pad "18" smd rect
			(at 0.19939 -2.8194 180)
			(size 0.2032 1.524)
			(layers "F.Cu" "F.Mask" "F.Paste")
			(net "HOST4_RST_N")
		)
		(pad "19" smd rect
			(at -0.19939 -2.8194 180)
			(size 0.2032 1.524)
			(layers "F.Cu" "F.Mask" "F.Paste")
			(net "HOST3_RST_N")
		)
		(pad "20" smd rect
			(at -0.59944 -2.8194 180)
			(size 0.2032 1.524)
			(layers "F.Cu" "F.Mask" "F.Paste")
			(net "HOST2_RST_N")
		)
		(pad "21" smd rect
			(at -0.99949 -2.8194 180)
			(size 0.2032 1.524)
			(layers "F.Cu" "F.Mask" "F.Paste")
			(net "HOST1_RST_N_R")
		)
		(pad "22" smd rect
			(at -1.39954 -2.8194 180)
			(size 0.2032 1.524)
			(layers "F.Cu" "F.Mask" "F.Paste")
			(net "Q3202_D")
		)
		(pad "23" smd rect
			(at -1.79959 -2.8194 180)
			(size 0.2032 1.524)
			(layers "F.Cu" "F.Mask" "F.Paste")
			(net "P3V3_STBY")
		)
		(pad "24" smd rect
			(at -2.19964 -2.8194 180)
			(size 0.2032 1.524)
			(layers "F.Cu" "F.Mask" "F.Paste")
			(net "P3V3_STBY")
		)
	)
	(footprint ""
		(layer "F.Cu")
		(at 35.941 -117.1956 90)
		(property "Reference" "TP241"
			(at 0 0 90)
			(layer "F.SilkS")
			(hide yes)
			(effects
				(font
					(size 1.27 1.27)
				)
			)
		)
		(property "Value" "TPAD28-2-GP"
			(at -0.0127 -1.6637 90)
			(unlocked yes)
			(layer "F.Fab")
			(hide yes)
			(effects
				(font
					(size 1.016 1.016)
					(thickness 0.1524)
				)
			)
		)
		(property "Device Type" "TPAD28"
			(at -0.0127 -3.1877 90)
			(unlocked yes)
			(layer "F.Fab")
			(hide yes)
			(effects
				(font
					(size 1.016 1.016)
					(thickness 0.1524)
				)
			)
		)
		(duplicate_pad_numbers_are_jumpers no)
		(fp_poly
			(pts
				(arc
					(start 0 0.3556)
					(mid 0 -0.3556)
					(end 0 0.3556)
				)
			)
			(stroke
				(width 0)
				(type default)
			)
			(fill no)
			(layer "F.CrtYd")
		)
		(fp_poly
			(pts
				(arc
					(start 0 0.6096)
					(mid 0 -0.6096)
					(end 0 0.6096)
				)
			)
			(stroke
				(width 0)
				(type default)
			)
			(fill no)
			(layer "F.Fab")
		)
		(pad "1" smd circle
			(at 0 0 90)
			(size 0.7112 0.7112)
			(layers "F.Cu" "F.Mask" "F.Paste")
			(net "TP_GPIOE7")
		)
	)
	(footprint ""
		(layer "F.Cu")
		(at 286.4866 -32.9692 90)
		(property "Reference" "C9"
			(at 0 0 90)
			(layer "F.SilkS")
			(hide yes)
			(effects
				(font
					(size 1.27 1.27)
				)
			)
		)
		(property "Value" "SCD22U10V2KX-1GP"
			(at 1.1811 -2.7051 90)
			(unlocked yes)
			(layer "F.Fab")
			(hide yes)
			(effects
				(font
					(size 1.016 1.016)
					(thickness 0.1524)
				)
			)
		)
		(property "Device Type" "C402H22"
			(at 1.1811 -4.2291 90)
			(unlocked yes)
			(layer "F.Fab")
			(hide yes)
			(effects
				(font
					(size 1.016 1.016)
					(thickness 0.1524)
				)
			)
		)
		(duplicate_pad_numbers_are_jumpers no)
		(fp_rect
			(start -0.4318 0.9525)
			(end 0.4318 -0.9525)
			(stroke
				(width 0)
				(type default)
			)
			(fill no)
			(layer "F.CrtYd")
		)
		(fp_rect
			(start -0.4318 0.9525)
			(end 0.4318 -0.9525)
			(stroke
				(width 0)
				(type default)
			)
			(fill no)
			(layer "F.Fab")
		)
		(pad "1" smd custom
			(at 0 -0.4445 90)
			(size 0.1524 0.1524)
			(layers "F.Cu" "F.Mask" "F.Paste")
			(net "PCIE_TX_CAP_P2")
			(options
				(clearance outline)
				(anchor circle)
			)
			(primitives
				(gr_poly
					(pts
						(arc
							(start 0.3048 -0.2032)
							(mid 0.275042 -0.275042)
							(end 0.2032 -0.3048)
						)
						(arc
							(start -0.2032 -0.3048)
							(mid -0.275042 -0.275042)
							(end -0.3048 -0.2032)
						)
						(arc
							(start -0.3048 0.2032)
							(mid -0.275042 0.275042)
							(end -0.2032 0.3048)
						)
						(arc
							(start 0.2032 0.3048)
							(mid 0.275042 0.275042)
							(end 0.3048 0.2032)
						)
					)
					(width 0)
					(fill yes)
				)
			)
		)
		(pad "2" smd custom
			(at 0 0.4445 90)
			(size 0.1524 0.1524)
			(layers "F.Cu" "F.Mask" "F.Paste")
			(net "PCIE_TX_P2")
			(options
				(clearance outline)
				(anchor circle)
			)
			(primitives
				(gr_poly
					(pts
						(arc
							(start 0.3048 -0.2032)
							(mid 0.275042 -0.275042)
							(end 0.2032 -0.3048)
						)
						(arc
							(start -0.2032 -0.3048)
							(mid -0.275042 -0.275042)
							(end -0.3048 -0.2032)
						)
						(arc
							(start -0.3048 0.2032)
							(mid -0.275042 0.275042)
							(end -0.2032 0.3048)
						)
						(arc
							(start 0.2032 0.3048)
							(mid 0.275042 0.275042)
							(end 0.3048 0.2032)
						)
					)
					(width 0)
					(fill yes)
				)
			)
		)
	)
	(footprint ""
		(layer "F.Cu")
		(at 36.432998 -103.386636 -90)
		(property "Reference" "C371"
			(at 0 0 270)
			(layer "F.SilkS")
			(hide yes)
			(effects
				(font
					(size 1.27 1.27)
				)
			)
		)
		(property "Value" "SCD1U16V2KX-3GP"
			(at 1.1811 -2.7051 270)
			(unlocked yes)
			(layer "F.Fab")
			(hide yes)
			(effects
				(font
					(size 1.016 1.016)
					(thickness 0.1524)
				)
			)
		)
		(property "Device Type" "C402H22"
			(at 1.1811 -4.2291 270)
			(unlocked yes)
			(layer "F.Fab")
			(hide yes)
			(effects
				(font
					(size 1.016 1.016)
					(thickness 0.1524)
				)
			)
		)
		(duplicate_pad_numbers_are_jumpers no)
		(fp_rect
			(start -0.4318 0.9525)
			(end 0.4318 -0.9525)
			(stroke
				(width 0)
				(type default)
			)
			(fill no)
			(layer "F.CrtYd")
		)
		(fp_rect
			(start -0.4318 0.9525)
			(end 0.4318 -0.9525)
			(stroke
				(width 0)
				(type default)
			)
			(fill no)
			(layer "F.Fab")
		)
		(pad "1" smd custom
			(at 0 -0.4445 270)
			(size 0.1524 0.1524)
			(layers "F.Cu" "F.Mask" "F.Paste")
			(net "P3V3_STBY")
			(options
				(clearance outline)
				(anchor circle)
			)
			(primitives
				(gr_poly
					(pts
						(arc
							(start 0.3048 -0.2032)
							(mid 0.275042 -0.275042)
							(end 0.2032 -0.3048)
						)
						(arc
							(start -0.2032 -0.3048)
							(mid -0.275042 -0.275042)
							(end -0.3048 -0.2032)
						)
						(arc
							(start -0.3048 0.2032)
							(mid -0.275042 0.275042)
							(end -0.2032 0.3048)
						)
						(arc
							(start 0.2032 0.3048)
							(mid 0.275042 0.275042)
							(end 0.3048 0.2032)
						)
					)
					(width 0)
					(fill yes)
				)
			)
		)
		(pad "2" smd custom
			(at 0 0.4445 270)
			(size 0.1524 0.1524)
			(layers "F.Cu" "F.Mask" "F.Paste")
			(net "GND")
			(options
				(clearance outline)
				(anchor circle)
			)
			(primitives
				(gr_poly
					(pts
						(arc
							(start 0.3048 -0.2032)
							(mid 0.275042 -0.275042)
							(end 0.2032 -0.3048)
						)
						(arc
							(start -0.2032 -0.3048)
							(mid -0.275042 -0.275042)
							(end -0.3048 -0.2032)
						)
						(arc
							(start -0.3048 0.2032)
							(mid -0.275042 0.275042)
							(end -0.2032 0.3048)
						)
						(arc
							(start 0.2032 0.3048)
							(mid 0.275042 0.275042)
							(end 0.3048 0.2032)
						)
					)
					(width 0)
					(fill yes)
				)
			)
		)
	)
	(footprint ""
		(layer "F.Cu")
		(at 237.109 -23.241)
		(property "Reference" "R814"
			(at 0 0 0)
			(layer "F.SilkS")
			(hide yes)
			(effects
				(font
					(size 1.27 1.27)
				)
			)
		)
		(property "Value" "4K7R2F-GP"
			(at 0.064008 -3.993896 0)
			(unlocked yes)
			(layer "F.Fab")
			(hide yes)
			(effects
				(font
					(size 1.016 1.016)
					(thickness 0.1524)
				)
			)
		)
		(property "Device Type" "R402H16"
			(at 0.064008 -5.517896 0)
			(unlocked yes)
			(layer "F.Fab")
			(hide yes)
			(effects
				(font
					(size 1.016 1.016)
					(thickness 0.1524)
				)
			)
		)
		(duplicate_pad_numbers_are_jumpers no)
		(fp_line
			(start -0.508 -0.9398)
			(end -0.508 0.9398)
			(stroke
				(width 0.1524)
				(type default)
			)
			(layer "F.SilkS")
		)
		(fp_line
			(start 0.508 -0.9398)
			(end -0.508 -0.9398)
			(stroke
				(width 0.1524)
				(type default)
			)
			(layer "F.SilkS")
		)
		(fp_rect
			(start -0.508 0.9398)
			(end 0.508 -0.9398)
			(stroke
				(width 0)
				(type default)
			)
			(fill no)
			(layer "F.CrtYd")
		)
		(fp_rect
			(start -0.508 0.9398)
			(end 0.508 -0.9398)
			(stroke
				(width 0)
				(type default)
			)
			(fill no)
			(layer "F.Fab")
		)
		(pad "1" smd custom
			(at 0 -0.4445)
			(size 0.1397 0.1397)
			(layers "F.Cu" "F.Mask" "F.Paste")
			(net "GND")
			(options
				(clearance outline)
				(anchor circle)
			)
			(primitives
				(gr_poly
					(pts
						(arc
							(start -0.1778 -0.2794)
							(mid -0.249642 -0.249642)
							(end -0.2794 -0.1778)
						)
						(arc
							(start -0.2794 0.1778)
							(mid -0.249642 0.249642)
							(end -0.1778 0.2794)
						)
						(arc
							(start 0.1778 0.2794)
							(mid 0.249642 0.249642)
							(end 0.2794 0.1778)
						)
						(arc
							(start 0.2794 -0.1778)
							(mid 0.249642 -0.249642)
							(end 0.1778 -0.2794)
						)
					)
					(width 0)
					(fill yes)
				)
			)
		)
		(pad "2" smd custom
			(at 0 0.4445)
			(size 0.1397 0.1397)
			(layers "F.Cu" "F.Mask" "F.Paste")
			(net "BOOTSTRAP7")
			(options
				(clearance outline)
				(anchor circle)
			)
			(primitives
				(gr_poly
					(pts
						(arc
							(start -0.1778 -0.2794)
							(mid -0.249642 -0.249642)
							(end -0.2794 -0.1778)
						)
						(arc
							(start -0.2794 0.1778)
							(mid -0.249642 0.249642)
							(end -0.1778 0.2794)
						)
						(arc
							(start 0.1778 0.2794)
							(mid 0.249642 0.249642)
							(end 0.2794 0.1778)
						)
						(arc
							(start 0.2794 -0.1778)
							(mid 0.249642 -0.249642)
							(end 0.1778 -0.2794)
						)
					)
					(width 0)
					(fill yes)
				)
			)
		)
	)
)
